FILE_TYPE = CONNECTIVITY;
{Allegro Design Entry HDL 17.2-2016 S081 (4005846) 1/11/2022}
"PAGE_NUMBER" = 146;
0"NC";
END.
